# S9S_MB_2U (Grand Teton) — schematic netlist excerpt (pin names and nets, part order shuffled) for the footprints in the layout excerpt that follows; sources: Cadence DE-HDL packaged netlist, KiCad conversion of 03242023_DA0F0TMBIJ0_F0T_Motherboard_J_brd_V01_OCP.brd

C1387  Q_CAP  47UF 4V 20% X6S  pkg C0805  page 78 : A = PVNN_MAIN_CPU1 ; B = GND
R4505  Q_RES  33.2 1% CHIP  pkg 0402LF  page 183 : A = SMB_SML1_PMBUS_3V3AUX_PCH_SCL ; B = SMB_SML1_PMBUS_3V3AUX_PCH_SCL_1
R1383  Q_RES  1K 1% CHIP  pkg 0402LF  page 239 : A = P3V3_AUX ; B = JTAG_BMC_DBP_PREQ_N

(kicad_pcb
	(version 20260206)
	(generator "pcbnew")
	(generator_version "10.0")
	(general
		(thickness 1.6)
		(legacy_teardrops no)
	)
	(paper "A4")
	(title_block
		(title "03242023_DA0F0TMBIJ0_F0T_Motherboard_J_brd_V01_OCP.brd")
		(comment 1 "Grand Teton / footprints 5259-5261 of 6105")
	)
	(layers
		(0 "F.Cu" signal "TOP")
		(4 "In1.Cu" signal "GND")
		(6 "In2.Cu" signal "IN1")
		(8 "In3.Cu" signal "GND1")
		(10 "In4.Cu" signal "IN2")
		(12 "In5.Cu" signal "GND2")
		(14 "In6.Cu" signal "IN3")
		(16 "In7.Cu" signal "GND3")
		(18 "In8.Cu" signal "VCC")
		(20 "In9.Cu" signal "VCC1")
		(22 "In10.Cu" signal "GND4")
		(24 "In11.Cu" signal "IN4")
		(26 "In12.Cu" signal "GND5")
		(28 "In13.Cu" signal "IN5")
		(30 "In14.Cu" signal "GND6")
		(32 "In15.Cu" signal "IN6")
		(34 "In16.Cu" signal "GND7")
		(2 "B.Cu" signal "BOTTOM")
		(9 "F.Adhes" user "F.Adhesive")
		(11 "B.Adhes" user "B.Adhesive")
		(13 "F.Paste" user "Package Geometry/Pastemask Top")
		(15 "B.Paste" user "Package Geometry/Pastemask Bottom")
		(5 "F.SilkS" user "Ref Des/Silkscreen Top")
		(7 "B.SilkS" user "Ref Des/Silkscreen Bottom")
		(1 "F.Mask" user "Board Geometry/Soldermask Top")
		(3 "B.Mask" user "Board Geometry/Soldermask Bottom")
		(17 "Dwgs.User" user "User.Drawings")
		(19 "Cmts.User" user "User.Comments")
		(21 "Eco1.User" user "User.Eco1")
		(23 "Eco2.User" user "User.Eco2")
		(25 "Edge.Cuts" user "Board Geometry/Outline")
		(27 "Margin" user)
		(31 "F.CrtYd" user "Package Geometry/Place Bound Top")
		(29 "B.CrtYd" user "Package Geometry/Place Bound Bottom")
		(35 "F.Fab" user "Ref Des/Assembly Top")
		(33 "B.Fab" user "Ref Des/Assembly Bottom")
	)
	(footprint ""
		(layer "B.Cu")
		(at 179.705 -19.522948 -90)
		(property "Reference" "R4505"
			(at 0 0 90)
			(layer "B.SilkS")
			(hide yes)
			(effects
				(font
					(size 1.27 1.27)
				)
				(justify mirror)
			)
		)
		(property "Value" ""
			(at 0 0 90)
			(layer "B.Fab")
			(effects
				(font
					(size 1.27 1.27)
				)
				(justify mirror)
			)
		)
		(duplicate_pad_numbers_are_jumpers no)
		(fp_line
			(start -0.7874 0.4064)
			(end 0.7874 0.4064)
			(stroke
				(width 0.1524)
				(type default)
			)
			(layer "B.SilkS")
		)
		(fp_line
			(start 0.7874 0.4064)
			(end 0.7874 -0.4064)
			(stroke
				(width 0.1524)
				(type default)
			)
			(layer "B.SilkS")
		)
		(fp_line
			(start -0.7874 -0.4064)
			(end -0.7874 0.4064)
			(stroke
				(width 0.1524)
				(type default)
			)
			(layer "B.SilkS")
		)
		(fp_line
			(start 0.7874 -0.4064)
			(end -0.7874 -0.4064)
			(stroke
				(width 0.1524)
				(type default)
			)
			(layer "B.SilkS")
		)
		(fp_line
			(start -0.67945 0.3048)
			(end -0.120396 0.3048)
			(stroke
				(width 0.1)
				(type default)
			)
			(layer "B.Fab")
		)
		(fp_line
			(start -0.120396 0.3048)
			(end -0.120396 0.2794)
			(stroke
				(width 0.1)
				(type default)
			)
			(layer "B.Fab")
		)
		(fp_line
			(start 0.12065 0.3048)
			(end 0.67945 0.3048)
			(stroke
				(width 0.1)
				(type default)
			)
			(layer "B.Fab")
		)
		(fp_line
			(start 0.67945 0.3048)
			(end 0.67945 -0.305054)
			(stroke
				(width 0.1)
				(type default)
			)
			(layer "B.Fab")
		)
		(fp_line
			(start -0.120396 0.2794)
			(end 0.12065 0.2794)
			(stroke
				(width 0.1)
				(type default)
			)
			(layer "B.Fab")
		)
		(fp_line
			(start 0.12065 0.2794)
			(end 0.12065 0.3048)
			(stroke
				(width 0.1)
				(type default)
			)
			(layer "B.Fab")
		)
		(fp_line
			(start -0.12065 -0.2794)
			(end -0.12065 -0.3048)
			(stroke
				(width 0.1)
				(type default)
			)
			(layer "B.Fab")
		)
		(fp_line
			(start 0.12065 -0.2794)
			(end -0.12065 -0.2794)
			(stroke
				(width 0.1)
				(type default)
			)
			(layer "B.Fab")
		)
		(fp_line
			(start -0.67945 -0.3048)
			(end -0.67945 0.3048)
			(stroke
				(width 0.1)
				(type default)
			)
			(layer "B.Fab")
		)
		(fp_line
			(start -0.12065 -0.3048)
			(end -0.67945 -0.3048)
			(stroke
				(width 0.1)
				(type default)
			)
			(layer "B.Fab")
		)
		(fp_line
			(start 0.12065 -0.305054)
			(end 0.12065 -0.2794)
			(stroke
				(width 0.1)
				(type default)
			)
			(layer "B.Fab")
		)
		(fp_line
			(start 0.67945 -0.305054)
			(end 0.12065 -0.305054)
			(stroke
				(width 0.1)
				(type default)
			)
			(layer "B.Fab")
		)
		(pad "1" smd circle
			(at 0.40005 0 90)
			(size 0 0)
			(layers "B.Cu" "B.Mask" "B.Paste")
			(net "SMB_SML1_PMBUS_3V3AUX_PCH_SCL")
		)
		(pad "2" smd circle
			(at -0.40005 0 90)
			(size 0 0)
			(layers "B.Cu" "B.Mask" "B.Paste")
			(net "SMB_SML1_PMBUS_3V3AUX_PCH_SCL_1")
		)
	)
	(footprint ""
		(layer "B.Cu")
		(at 107.457494 -238.04372 -90)
		(property "Reference" "C1387"
			(at 0 0 90)
			(layer "B.SilkS")
			(hide yes)
			(effects
				(font
					(size 1.27 1.27)
				)
				(justify mirror)
			)
		)
		(property "Value" ""
			(at 0 0 90)
			(layer "B.Fab")
			(effects
				(font
					(size 1.27 1.27)
				)
				(justify mirror)
			)
		)
		(duplicate_pad_numbers_are_jumpers no)
		(fp_line
			(start -1.524 0.762)
			(end 1.524 0.762)
			(stroke
				(width 0.1524)
				(type default)
			)
			(layer "B.SilkS")
		)
		(fp_line
			(start 1.524 0.762)
			(end 1.524 -0.762)
			(stroke
				(width 0.1524)
				(type default)
			)
			(layer "B.SilkS")
		)
		(fp_line
			(start -1.524 -0.762)
			(end -1.524 0.762)
			(stroke
				(width 0.1524)
				(type default)
			)
			(layer "B.SilkS")
		)
		(fp_line
			(start 1.524 -0.762)
			(end -1.524 -0.762)
			(stroke
				(width 0.1524)
				(type default)
			)
			(layer "B.SilkS")
		)
		(fp_line
			(start -1.1049 0.724916)
			(end -1.1049 -0.724916)
			(stroke
				(width 0.1)
				(type default)
			)
			(layer "B.Fab")
		)
		(fp_line
			(start 1.1049 0.724916)
			(end -1.1049 0.724916)
			(stroke
				(width 0.1)
				(type default)
			)
			(layer "B.Fab")
		)
		(fp_line
			(start -1.1049 -0.724916)
			(end 1.1049 -0.724916)
			(stroke
				(width 0.1)
				(type default)
			)
			(layer "B.Fab")
		)
		(fp_line
			(start 1.1049 -0.724916)
			(end 1.1049 0.724916)
			(stroke
				(width 0.1)
				(type default)
			)
			(layer "B.Fab")
		)
		(pad "1" smd rect
			(at 0.889 0 270)
			(size 1.016 1.27)
			(layers "B.Cu" "B.Mask" "B.Paste")
			(net "PVNN_MAIN_CPU1")
		)
		(pad "2" smd rect
			(at -0.889 0 270)
			(size 1.016 1.27)
			(layers "B.Cu" "B.Mask" "B.Paste")
			(net "GND")
		)
	)
	(footprint ""
		(layer "B.Cu")
		(at 144.399 -9.362948 -90)
		(property "Reference" "R1383"
			(at 0 0 90)
			(layer "B.SilkS")
			(hide yes)
			(effects
				(font
					(size 1.27 1.27)
				)
				(justify mirror)
			)
		)
		(property "Value" ""
			(at 0 0 90)
			(layer "B.Fab")
			(effects
				(font
					(size 1.27 1.27)
				)
				(justify mirror)
			)
		)
		(duplicate_pad_numbers_are_jumpers no)
		(fp_line
			(start -0.7874 0.4064)
			(end 0.7874 0.4064)
			(stroke
				(width 0.1524)
				(type default)
			)
			(layer "B.SilkS")
		)
		(fp_line
			(start 0.7874 0.4064)
			(end 0.7874 -0.4064)
			(stroke
				(width 0.1524)
				(type default)
			)
			(layer "B.SilkS")
		)
		(fp_line
			(start -0.7874 -0.4064)
			(end -0.7874 0.4064)
			(stroke
				(width 0.1524)
				(type default)
			)
			(layer "B.SilkS")
		)
		(fp_line
			(start 0.7874 -0.4064)
			(end -0.7874 -0.4064)
			(stroke
				(width 0.1524)
				(type default)
			)
			(layer "B.SilkS")
		)
		(fp_line
			(start -0.67945 0.3048)
			(end -0.120396 0.3048)
			(stroke
				(width 0.1)
				(type default)
			)
			(layer "B.Fab")
		)
		(fp_line
			(start -0.120396 0.3048)
			(end -0.120396 0.2794)
			(stroke
				(width 0.1)
				(type default)
			)
			(layer "B.Fab")
		)
		(fp_line
			(start 0.12065 0.3048)
			(end 0.67945 0.3048)
			(stroke
				(width 0.1)
				(type default)
			)
			(layer "B.Fab")
		)
		(fp_line
			(start 0.67945 0.3048)
			(end 0.67945 -0.305054)
			(stroke
				(width 0.1)
				(type default)
			)
			(layer "B.Fab")
		)
		(fp_line
			(start -0.120396 0.2794)
			(end 0.12065 0.2794)
			(stroke
				(width 0.1)
				(type default)
			)
			(layer "B.Fab")
		)
		(fp_line
			(start 0.12065 0.2794)
			(end 0.12065 0.3048)
			(stroke
				(width 0.1)
				(type default)
			)
			(layer "B.Fab")
		)
		(fp_line
			(start -0.12065 -0.2794)
			(end -0.12065 -0.3048)
			(stroke
				(width 0.1)
				(type default)
			)
			(layer "B.Fab")
		)
		(fp_line
			(start 0.12065 -0.2794)
			(end -0.12065 -0.2794)
			(stroke
				(width 0.1)
				(type default)
			)
			(layer "B.Fab")
		)
		(fp_line
			(start -0.67945 -0.3048)
			(end -0.67945 0.3048)
			(stroke
				(width 0.1)
				(type default)
			)
			(layer "B.Fab")
		)
		(fp_line
			(start -0.12065 -0.3048)
			(end -0.67945 -0.3048)
			(stroke
				(width 0.1)
				(type default)
			)
			(layer "B.Fab")
		)
		(fp_line
			(start 0.12065 -0.305054)
			(end 0.12065 -0.2794)
			(stroke
				(width 0.1)
				(type default)
			)
			(layer "B.Fab")
		)
		(fp_line
			(start 0.67945 -0.305054)
			(end 0.12065 -0.305054)
			(stroke
				(width 0.1)
				(type default)
			)
			(layer "B.Fab")
		)
		(pad "1" smd circle
			(at 0.40005 0 90)
			(size 0 0)
			(layers "B.Cu" "B.Mask" "B.Paste")
			(net "P3V3_AUX")
		)
		(pad "2" smd circle
			(at -0.40005 0 90)
			(size 0 0)
			(layers "B.Cu" "B.Mask" "B.Paste")
			(net "JTAG_BMC_DBP_PREQ_N")
		)
	)
)
